# T6G (Grand Teton) — schematic netlist excerpt (pin names and nets, part order shuffled) for the footprints in the layout excerpt that follows; sources: Cadence DE-HDL packaged netlist, KiCad conversion of 04192023_DAF0TMB3IC0_F0TG_MB_C_brd_V02_OCP.brd

R1475  Q_RES  10K 1% EMPTY  pkg 0402LF  page 169 : A = P3V3_AUX_DSC_G2 ; B = GND
PC375_1  Q_CAP  0.1UF 25V 10% X7R  pkg 0402  page 218 : A = SW_P12V_AUX_PVDDCR_CPU1_P1_FLT ; B = GND
C838  Q_CAP_DIFFBUS  DIFF BUS_0.22UF 6.3V 20% X6S  pkg C0201  page 64 : \1\ = P5E_CPU0_P2_TX_C_DN<15> ; \2\ = P5E_CPU0_P2_TX_DN<15>

(kicad_pcb
	(version 20260206)
	(generator "pcbnew")
	(generator_version "10.0")
	(general
		(thickness 1.6)
		(legacy_teardrops no)
	)
	(paper "A4")
	(title_block
		(title "04192023_DAF0TMB3IC0_F0TG_MB_C_brd_V02_OCP.brd")
		(comment 1 "Grand Teton / footprints 1094-1096 of 8354")
	)
	(layers
		(0 "F.Cu" signal "TOP")
		(4 "In1.Cu" signal "GND")
		(6 "In2.Cu" signal "IN1")
		(8 "In3.Cu" signal "GND1")
		(10 "In4.Cu" signal "IN2")
		(12 "In5.Cu" signal "GND2")
		(14 "In6.Cu" signal "IN3")
		(16 "In7.Cu" signal "GND3")
		(18 "In8.Cu" signal "VCC")
		(20 "In9.Cu" signal "VCC1")
		(22 "In10.Cu" signal "GND4")
		(24 "In11.Cu" signal "IN4")
		(26 "In12.Cu" signal "GND5")
		(28 "In13.Cu" signal "IN5")
		(30 "In14.Cu" signal "GND6")
		(32 "In15.Cu" signal "IN6")
		(34 "In16.Cu" signal "GND7")
		(2 "B.Cu" signal "BOTTOM")
		(9 "F.Adhes" user "F.Adhesive")
		(11 "B.Adhes" user "B.Adhesive")
		(13 "F.Paste" user "Package Geometry/Pastemask Top")
		(15 "B.Paste" user "Package Geometry/Pastemask Bottom")
		(5 "F.SilkS" user "Ref Des/Silkscreen Top")
		(7 "B.SilkS" user "Ref Des/Silkscreen Bottom")
		(1 "F.Mask" user "Board Geometry/Soldermask Top")
		(3 "B.Mask" user "Board Geometry/Soldermask Bottom")
		(17 "Dwgs.User" user "User.Drawings")
		(19 "Cmts.User" user "User.Comments")
		(21 "Eco1.User" user "User.Eco1")
		(23 "Eco2.User" user "User.Eco2")
		(25 "Edge.Cuts" user "Board Geometry/Outline")
		(27 "Margin" user)
		(31 "F.CrtYd" user "Package Geometry/Place Bound Top")
		(29 "B.CrtYd" user "Package Geometry/Place Bound Bottom")
		(35 "F.Fab" user "Ref Des/Assembly Top")
		(33 "B.Fab" user "Ref Des/Assembly Bottom")
	)
	(footprint ""
		(layer "F.Cu")
		(at 82.986118 -339.362796)
		(property "Reference" "PC375_1"
			(at 0 0 0)
			(layer "F.SilkS")
			(hide yes)
			(effects
				(font
					(size 1.27 1.27)
				)
			)
		)
		(property "Value" ""
			(at 0 0 0)
			(layer "F.Fab")
			(effects
				(font
					(size 1.27 1.27)
				)
			)
		)
		(duplicate_pad_numbers_are_jumpers no)
		(fp_line
			(start -0.7874 -0.4064)
			(end 0.7874 -0.4064)
			(stroke
				(width 0.1524)
				(type default)
			)
			(layer "F.SilkS")
		)
		(fp_line
			(start -0.7874 0.4064)
			(end -0.7874 -0.4064)
			(stroke
				(width 0.1524)
				(type default)
			)
			(layer "F.SilkS")
		)
		(fp_line
			(start 0.7874 -0.4064)
			(end 0.7874 0.4064)
			(stroke
				(width 0.1524)
				(type default)
			)
			(layer "F.SilkS")
		)
		(fp_line
			(start 0.7874 0.4064)
			(end -0.7874 0.4064)
			(stroke
				(width 0.1524)
				(type default)
			)
			(layer "F.SilkS")
		)
		(fp_line
			(start -0.67945 -0.305054)
			(end -0.12065 -0.305054)
			(stroke
				(width 0.1)
				(type default)
			)
			(layer "F.Fab")
		)
		(fp_line
			(start -0.67945 0.3048)
			(end -0.67945 -0.305054)
			(stroke
				(width 0.1)
				(type default)
			)
			(layer "F.Fab")
		)
		(fp_line
			(start -0.12065 -0.305054)
			(end -0.12065 -0.2794)
			(stroke
				(width 0.1)
				(type default)
			)
			(layer "F.Fab")
		)
		(fp_line
			(start -0.12065 -0.2794)
			(end 0.12065 -0.2794)
			(stroke
				(width 0.1)
				(type default)
			)
			(layer "F.Fab")
		)
		(fp_line
			(start -0.12065 0.2794)
			(end -0.12065 0.3048)
			(stroke
				(width 0.1)
				(type default)
			)
			(layer "F.Fab")
		)
		(fp_line
			(start -0.12065 0.3048)
			(end -0.67945 0.3048)
			(stroke
				(width 0.1)
				(type default)
			)
			(layer "F.Fab")
		)
		(fp_line
			(start 0.120396 0.2794)
			(end -0.12065 0.2794)
			(stroke
				(width 0.1)
				(type default)
			)
			(layer "F.Fab")
		)
		(fp_line
			(start 0.120396 0.3048)
			(end 0.120396 0.2794)
			(stroke
				(width 0.1)
				(type default)
			)
			(layer "F.Fab")
		)
		(fp_line
			(start 0.12065 -0.3048)
			(end 0.67945 -0.3048)
			(stroke
				(width 0.1)
				(type default)
			)
			(layer "F.Fab")
		)
		(fp_line
			(start 0.12065 -0.2794)
			(end 0.12065 -0.3048)
			(stroke
				(width 0.1)
				(type default)
			)
			(layer "F.Fab")
		)
		(fp_line
			(start 0.67945 -0.3048)
			(end 0.67945 0.3048)
			(stroke
				(width 0.1)
				(type default)
			)
			(layer "F.Fab")
		)
		(fp_line
			(start 0.67945 0.3048)
			(end 0.120396 0.3048)
			(stroke
				(width 0.1)
				(type default)
			)
			(layer "F.Fab")
		)
		(pad "1" smd circle
			(at -0.40005 0)
			(size 0 0)
			(layers "F.Cu" "F.Mask" "F.Paste")
			(net "SW_P12V_AUX_PVDDCR_CPU1_P1_FLT")
		)
		(pad "2" smd circle
			(at 0.40005 0)
			(size 0 0)
			(layers "F.Cu" "F.Mask" "F.Paste")
			(net "GND")
		)
	)
	(footprint ""
		(layer "F.Cu")
		(at 45.71492 -111.32058 180)
		(property "Reference" "R1475"
			(at 0 0 180)
			(layer "F.SilkS")
			(hide yes)
			(effects
				(font
					(size 1.27 1.27)
				)
			)
		)
		(property "Value" ""
			(at 0 0 180)
			(layer "F.Fab")
			(effects
				(font
					(size 1.27 1.27)
				)
			)
		)
		(duplicate_pad_numbers_are_jumpers no)
		(fp_line
			(start 0.7874 0.4064)
			(end -0.7874 0.4064)
			(stroke
				(width 0.1524)
				(type default)
			)
			(layer "F.SilkS")
		)
		(fp_line
			(start 0.7874 -0.4064)
			(end 0.7874 0.4064)
			(stroke
				(width 0.1524)
				(type default)
			)
			(layer "F.SilkS")
		)
		(fp_line
			(start -0.7874 0.4064)
			(end -0.7874 -0.4064)
			(stroke
				(width 0.1524)
				(type default)
			)
			(layer "F.SilkS")
		)
		(fp_line
			(start -0.7874 -0.4064)
			(end 0.7874 -0.4064)
			(stroke
				(width 0.1524)
				(type default)
			)
			(layer "F.SilkS")
		)
		(fp_line
			(start 0.67945 0.3048)
			(end 0.120396 0.3048)
			(stroke
				(width 0.1)
				(type default)
			)
			(layer "F.Fab")
		)
		(fp_line
			(start 0.67945 -0.3048)
			(end 0.67945 0.3048)
			(stroke
				(width 0.1)
				(type default)
			)
			(layer "F.Fab")
		)
		(fp_line
			(start 0.12065 -0.2794)
			(end 0.12065 -0.3048)
			(stroke
				(width 0.1)
				(type default)
			)
			(layer "F.Fab")
		)
		(fp_line
			(start 0.12065 -0.3048)
			(end 0.67945 -0.3048)
			(stroke
				(width 0.1)
				(type default)
			)
			(layer "F.Fab")
		)
		(fp_line
			(start 0.120396 0.3048)
			(end 0.120396 0.2794)
			(stroke
				(width 0.1)
				(type default)
			)
			(layer "F.Fab")
		)
		(fp_line
			(start 0.120396 0.2794)
			(end -0.12065 0.2794)
			(stroke
				(width 0.1)
				(type default)
			)
			(layer "F.Fab")
		)
		(fp_line
			(start -0.12065 0.3048)
			(end -0.67945 0.3048)
			(stroke
				(width 0.1)
				(type default)
			)
			(layer "F.Fab")
		)
		(fp_line
			(start -0.12065 0.2794)
			(end -0.12065 0.3048)
			(stroke
				(width 0.1)
				(type default)
			)
			(layer "F.Fab")
		)
		(fp_line
			(start -0.12065 -0.2794)
			(end 0.12065 -0.2794)
			(stroke
				(width 0.1)
				(type default)
			)
			(layer "F.Fab")
		)
		(fp_line
			(start -0.12065 -0.305054)
			(end -0.12065 -0.2794)
			(stroke
				(width 0.1)
				(type default)
			)
			(layer "F.Fab")
		)
		(fp_line
			(start -0.67945 0.3048)
			(end -0.67945 -0.305054)
			(stroke
				(width 0.1)
				(type default)
			)
			(layer "F.Fab")
		)
		(fp_line
			(start -0.67945 -0.305054)
			(end -0.12065 -0.305054)
			(stroke
				(width 0.1)
				(type default)
			)
			(layer "F.Fab")
		)
		(pad "1" smd circle
			(at -0.40005 0 180)
			(size 0 0)
			(layers "F.Cu" "F.Mask" "F.Paste")
			(net "P3V3_AUX_DSC_G2")
		)
		(pad "2" smd circle
			(at 0.40005 0 180)
			(size 0 0)
			(layers "F.Cu" "F.Mask" "F.Paste")
			(net "GND")
		)
	)
	(footprint ""
		(layer "F.Cu")
		(at 425.36872 -388.767828)
		(property "Reference" "C838"
			(at 0 0 0)
			(layer "F.SilkS")
			(hide yes)
			(effects
				(font
					(size 1.27 1.27)
				)
			)
		)
		(property "Value" ""
			(at 0 0 0)
			(layer "F.Fab")
			(effects
				(font
					(size 1.27 1.27)
				)
			)
		)
		(duplicate_pad_numbers_are_jumpers no)
		(fp_line
			(start -0.299974 -0.150114)
			(end 0.299974 -0.150114)
			(stroke
				(width 0.1)
				(type default)
			)
			(layer "F.Fab")
		)
		(fp_line
			(start -0.299974 0.150114)
			(end -0.299974 -0.150114)
			(stroke
				(width 0.1)
				(type default)
			)
			(layer "F.Fab")
		)
		(fp_line
			(start 0.299974 -0.150114)
			(end 0.299974 0.150114)
			(stroke
				(width 0.1)
				(type default)
			)
			(layer "F.Fab")
		)
		(fp_line
			(start 0.299974 0.150114)
			(end -0.299974 0.150114)
			(stroke
				(width 0.1)
				(type default)
			)
			(layer "F.Fab")
		)
		(pad "1" smd rect
			(at -0.2667 0)
			(size 0.3048 0.381)
			(layers "F.Cu" "F.Mask" "F.Paste")
			(net "P5E_CPU0_P2_TX_C_DN<15>")
		)
		(pad "2" smd rect
			(at 0.2667 0)
			(size 0.3048 0.381)
			(layers "F.Cu" "F.Mask" "F.Paste")
			(net "P5E_CPU0_P2_TX_DN<15>")
		)
	)
)
